FILE_TYPE = MACRO_DRAWING;
SET COLOR_WIRE YELLOW;
SET COLOR_PROP ORANGE;
SET COLOR_DOT WHITE;
SET COLOR_ARC YELLOW;
SET COLOR_BODY GREEN;
SET COLOR_NOTE PURPLE;
SET PROP_DISPLAY VALUE;
SET PAGE_NUMBER P65;
FORCEADD QUANTA_TITLE_BLOCK_C..1
(0 0);
FORCEPROP 1 LAST CUSTOM_TXT_CDS <NAME_2>
J 0
(-3175 50);
FORCEPROP 1 LAST CUSTOM_TXT_CDS <NAME_1>
J 0
(-3175 175);
FORCEPROP 1 LAST CUSTOM_TXT_CDS <Q_NUMBER>
J 0
(-1403 103);
DISPLAY 1.212766 (-1403 103);
FORCEPROP 1 LAST CUSTOM_TXT_CDS <Q_PROJ>
J 0
(-2382 102);
DISPLAY 1.212766 (-2382 102);
FORCEPROP 1 LAST CUSTOM_TXT_CDS <Q_REV>
J 0
(-184 103);
DISPLAY 1.212766 (-184 103);
FORCEPROP 1 LAST CUSTOM_TXT_CDS <CON_LAST_MODIFIED>
J 0
(-1885 15);
DISPLAY 0.978723 (-1885 15);
FORCEPROP 1 LAST CUSTOM_TXT_CDS <CON_PAGE_NUM> OF <CON_TOTAL_PAGES>
J 0
(-446 18);
DISPLAY 0.978723 (-446 18);
FORCEPROP 1 LAST Q_DEPT BU9
J 1
(-3763 49);
DISPLAY 1.957447 (-3763 49);
PAINT GREEN (-3763 49);
FORCEPROP 1 LAST Q_TITLE AC CAPS CPU1 P0/P1 TX
J 0
(-9366 26);
DISPLAY 2.446809 (-9366 26);
PAINT GREEN (-9366 26);
FORCEPROP 2 LAST CDS_LIB pure_quanta
J 0
(0 0);
DISPLAY INVISIBLE (0 0);
FORCEPROP 1 LAST CDS_LMAN_SYM_OUTLINE -9475,6775,100,-125
J 0
(0 0);
DISPLAY 0.468085 (0 0);
PAINT GREEN (0 0);
DISPLAY INVISIBLE (0 0);
FORCEPROP 2 LAST PAGE_BORDER TRUE
J 0
(-7890 5250);
DISPLAY 0.638298 (-7890 5250);
PAINT PINK (-7890 5250);
DISPLAY INVISIBLE (-7890 5250);
FORCEPROP 1 LAST COMMENT_BODY TRUE
J 0
(12 -13);
DISPLAY 0.978723 (12 -13);
PAINT GREEN (12 -13);
DISPLAY INVISIBLE (12 -13);
FORCEPROP 2 LAST CDS_XR_PAGE_TITLE CR-65 : @T6G_MB_LIB.T6G(SCH_1):PAGE65
J 0
(-7890 5250);
DISPLAY 0.638298 (-7890 5250);
PAINT PINK (-7890 5250);
DISPLAY INVISIBLE (-7890 5250);
FORCEPROP 2 LAST CUSTOM_TXT_CDS <XR_PAGE_TITLE>
J 0
(-7890 5250);
DISPLAY 0.638298 (-7890 5250);
PAINT PINK (-7890 5250);
DISPLAY INVISIBLE (-7890 5250);
FORCEPROP 0 LAST CDS_CON_LAST_MODIFIED Thu Mar 10 20:15:17 2022
J 0
(-1885 15);
DISPLAY INVISIBLE (-1885 15);
QUIT
